(kicad_pcb
	(version 20241229)
	(generator "pcbnew")
	(generator_version "9.0")
	(general
		(thickness 1.292)
		(legacy_teardrops no)
	)
	(paper "A4")
	(title_block
		(title "LPDDR5 Testbed")
		(date "2023-12-19")
		(rev "1.0.0")
		(comment 9 "footprints 8-11 of 160")
	)
	(layers
		(0 "F.Cu" signal)
		(4 "In1.Cu" power)
		(6 "In2.Cu" power)
		(8 "In3.Cu" signal)
		(10 "In4.Cu" signal)
		(2 "B.Cu" signal)
		(9 "F.Adhes" user "F.Adhesive")
		(11 "B.Adhes" user "B.Adhesive")
		(13 "F.Paste" user)
		(15 "B.Paste" user)
		(5 "F.SilkS" user "F.Silkscreen")
		(7 "B.SilkS" user "B.Silkscreen")
		(1 "F.Mask" user)
		(3 "B.Mask" user)
		(17 "Dwgs.User" user "User.Drawings")
		(19 "Cmts.User" user "User.Comments")
		(21 "Eco1.User" user "User.Eco1")
		(23 "Eco2.User" user "User.Eco2")
		(25 "Edge.Cuts" user)
		(27 "Margin" user)
		(31 "F.CrtYd" user "F.Courtyard")
		(29 "B.CrtYd" user "B.Courtyard")
		(35 "F.Fab" user)
		(33 "B.Fab" user)
	)
	(footprint "antmicro-footprints:C_0603_1608Metric"
		(layer "F.Cu")
		(at 105.425 62.575 180)
		(descr "Capacitor SMD 0603")
		(tags "capacitor 0603")
		(property "Reference" "C16"
			(at -1.075 -1.325 0)
			(unlocked yes)
			(layer "F.SilkS")
			(effects
				(font
					(size 0.7 0.7)
					(thickness 0.15)
				)
				(justify right bottom)
			)
		)
		(property "Value" "C_22u_0603"
			(at -1.42757 1.770288 0)
			(layer "F.Fab")
			(effects
				(font
					(size 0.7 0.7)
					(thickness 0.15)
				)
				(justify right bottom)
			)
		)
		(property "Author" "Antmicro"
			(at 210.85 125.15 0)
			(layer "F.Fab")
			(hide yes)
			(effects
				(font
					(size 1 1)
					(thickness 0.15)
				)
			)
		)
		(property "Dielectric" ""
			(at 210.85 125.15 0)
			(layer "F.Fab")
			(hide yes)
			(effects
				(font
					(size 1 1)
					(thickness 0.15)
				)
			)
		)
		(property "License" "Apache-2.0"
			(at 210.85 125.15 0)
			(layer "F.Fab")
			(hide yes)
			(effects
				(font
					(size 1 1)
					(thickness 0.15)
				)
			)
		)
		(property "MPN" "GRM188R60J226MEA0D"
			(at 210.85 125.15 0)
			(layer "F.Fab")
			(hide yes)
			(effects
				(font
					(size 1 1)
					(thickness 0.15)
				)
			)
		)
		(property "Manufacturer" "Murata"
			(at 210.85 125.15 0)
			(layer "F.Fab")
			(hide yes)
			(effects
				(font
					(size 1 1)
					(thickness 0.15)
				)
			)
		)
		(property "Val" "22u"
			(at 210.85 125.15 0)
			(layer "F.Fab")
			(hide yes)
			(effects
				(font
					(size 1 1)
					(thickness 0.15)
				)
			)
		)
		(property "Voltage" ""
			(at 210.85 125.15 0)
			(layer "F.Fab")
			(hide yes)
			(effects
				(font
					(size 1 1)
					(thickness 0.15)
				)
			)
		)
		(sheetname "Power supply")
		(sheetfile "power_supply.kicad_sch")
		(attr smd)
		(fp_line
			(start -0.3 0.3)
			(end 0.3 0.3)
			(stroke
				(width 0.15)
				(type solid)
			)
			(layer "F.SilkS")
		)
		(fp_line
			(start -0.3 -0.3)
			(end 0.3 -0.3)
			(stroke
				(width 0.15)
				(type solid)
			)
			(layer "F.SilkS")
		)
		(fp_rect
			(start -1.24 -0.7)
			(end 1.24 0.7)
			(stroke
				(width 0.05)
				(type solid)
			)
			(fill no)
			(layer "F.CrtYd")
		)
		(fp_rect
			(start -0.8 -0.4)
			(end 0.8 0.4)
			(stroke
				(width 0.15)
				(type solid)
			)
			(fill no)
			(layer "F.Fab")
		)
		(pad "1" smd roundrect
			(at -0.7 0 180)
			(size 0.6 0.8)
			(layers "F.Cu" "F.Mask" "F.Paste")
			(roundrect_rratio 0.2)
			(net 14 "GND")
			(pintype "passive")
		)
		(pad "2" smd roundrect
			(at 0.7 0 180)
			(size 0.6 0.8)
			(layers "F.Cu" "F.Mask" "F.Paste")
			(roundrect_rratio 0.2)
			(net 7 "/Power supply/VOUT1")
			(pintype "passive")
		)
	)
	(footprint "antmicro-footprints:C_0805_2012Metric"
		(layer "F.Cu")
		(at 106.4875 73.225)
		(descr "Capacitor SMD 0805")
		(tags "capacitor SMD 0805")
		(property "Reference" "C10"
			(at 2.4125 2.275 0)
			(unlocked yes)
			(layer "F.SilkS")
			(effects
				(font
					(size 0.7 0.7)
					(thickness 0.15)
				)
				(justify left bottom)
			)
		)
		(property "Value" "C_22u_25V_0805"
			(at -2.055717 1.963152 0)
			(layer "F.Fab")
			(effects
				(font
					(size 0.7 0.7)
					(thickness 0.15)
				)
				(justify left bottom)
			)
		)
		(property "Author" "Antmicro"
			(at 0 0 0)
			(layer "F.Fab")
			(hide yes)
			(effects
				(font
					(size 1 1)
					(thickness 0.15)
				)
			)
		)
		(property "Dielectric" ""
			(at 0 0 0)
			(layer "F.Fab")
			(hide yes)
			(effects
				(font
					(size 1 1)
					(thickness 0.15)
				)
			)
		)
		(property "License" "Apache-2.0"
			(at 0 0 0)
			(layer "F.Fab")
			(hide yes)
			(effects
				(font
					(size 1 1)
					(thickness 0.15)
				)
			)
		)
		(property "MPN" "CL21A226MAYNNNE"
			(at 0 0 0)
			(layer "F.Fab")
			(hide yes)
			(effects
				(font
					(size 1 1)
					(thickness 0.15)
				)
			)
		)
		(property "Manufacturer" "Samsung Electro-Mechanics"
			(at 0 0 0)
			(layer "F.Fab")
			(hide yes)
			(effects
				(font
					(size 1 1)
					(thickness 0.15)
				)
			)
		)
		(property "Val" "22u_25V"
			(at 0 0 0)
			(layer "F.Fab")
			(hide yes)
			(effects
				(font
					(size 1 1)
					(thickness 0.15)
				)
			)
		)
		(property "Voltage" ""
			(at 0 0 0)
			(layer "F.Fab")
			(hide yes)
			(effects
				(font
					(size 1 1)
					(thickness 0.15)
				)
			)
		)
		(sheetname "Power supply")
		(sheetfile "power_supply.kicad_sch")
		(attr smd)
		(fp_line
			(start -0.3 -0.8)
			(end 0.3 -0.8)
			(stroke
				(width 0.15)
				(type solid)
			)
			(layer "F.SilkS")
		)
		(fp_line
			(start -0.3 0.8)
			(end 0.3 0.8)
			(stroke
				(width 0.15)
				(type solid)
			)
			(layer "F.SilkS")
		)
		(fp_rect
			(start -1.9 -0.93)
			(end 1.9 0.93)
			(stroke
				(width 0.05)
				(type solid)
			)
			(fill no)
			(layer "F.CrtYd")
		)
		(fp_rect
			(start -0.95 -0.675)
			(end 0.95 0.675)
			(stroke
				(width 0.15)
				(type solid)
			)
			(fill no)
			(layer "F.Fab")
		)
		(pad "1" smd rect
			(at -1.05 0)
			(size 1.2 1.2)
			(layers "F.Cu" "F.Mask" "F.Paste")
			(net 14 "GND")
			(pintype "passive")
		)
		(pad "2" smd rect
			(at 1.05 0)
			(size 1.2 1.2)
			(layers "F.Cu" "F.Mask" "F.Paste")
			(net 5 "+5V")
			(pintype "passive")
		)
	)
	(footprint "antmicro-footprints:R_Array_4x0402_Panasonic_EXB28V"
		(layer "F.Cu")
		(at 141.6 93.8 180)
		(property "Reference" "R76"
			(at -1 1.4 0)
			(unlocked yes)
			(layer "F.SilkS")
			(effects
				(font
					(size 0.7 0.7)
					(thickness 0.15)
				)
				(justify right bottom)
			)
		)
		(property "Value" "R_4x100R_0402_array"
			(at -1.5 2 0)
			(layer "F.Fab")
			(effects
				(font
					(size 0.7 0.7)
					(thickness 0.15)
				)
				(justify right bottom)
			)
		)
		(property "Author" "Antmicro"
			(at 283.2 187.6 0)
			(layer "F.Fab")
			(hide yes)
			(effects
				(font
					(size 1 1)
					(thickness 0.15)
				)
			)
		)
		(property "License" "Apache-2.0"
			(at 283.2 187.6 0)
			(layer "F.Fab")
			(hide yes)
			(effects
				(font
					(size 1 1)
					(thickness 0.15)
				)
			)
		)
		(property "MPN" "EXB-28V101JX"
			(at 283.2 187.6 0)
			(layer "F.Fab")
			(hide yes)
			(effects
				(font
					(size 1 1)
					(thickness 0.15)
				)
			)
		)
		(property "Manufacturer" "Panasonic"
			(at 283.2 187.6 0)
			(layer "F.Fab")
			(hide yes)
			(effects
				(font
					(size 1 1)
					(thickness 0.15)
				)
			)
		)
		(property "Val" "R_4x100R_0402"
			(at 283.2 187.6 0)
			(layer "F.Fab")
			(hide yes)
			(effects
				(font
					(size 1 1)
					(thickness 0.15)
				)
			)
		)
		(sheetname "Translators1")
		(sheetfile "translators.kicad_sch")
		(attr smd)
		(fp_line
			(start 1.25 0.499)
			(end 1.25 -0.499)
			(stroke
				(width 0.15)
				(type solid)
			)
			(layer "F.SilkS")
		)
		(fp_line
			(start -1.25 -0.5)
			(end -1.25 0.498)
			(stroke
				(width 0.15)
				(type solid)
			)
			(layer "F.SilkS")
		)
		(fp_rect
			(start -1.25 -0.8)
			(end 1.25 0.8)
			(stroke
				(width 0.05)
				(type solid)
			)
			(fill no)
			(layer "F.CrtYd")
		)
		(fp_line
			(start 0.998 0.498)
			(end -1 0.498)
			(stroke
				(width 0.15)
				(type solid)
			)
			(layer "F.Fab")
		)
		(fp_line
			(start 0.998 -0.5)
			(end 0.998 0.498)
			(stroke
				(width 0.15)
				(type solid)
			)
			(layer "F.Fab")
		)
		(fp_line
			(start -1 0.498)
			(end -1 -0.5)
			(stroke
				(width 0.15)
				(type solid)
			)
			(layer "F.Fab")
		)
		(fp_line
			(start -1 -0.5)
			(end 0.998 -0.5)
			(stroke
				(width 0.15)
				(type solid)
			)
			(layer "F.Fab")
		)
		(pad "1" smd roundrect
			(at -0.8875 0.45 180)
			(size 0.525 0.5)
			(layers "F.Cu" "F.Mask" "F.Paste")
			(roundrect_rratio 0.25)
			(net 104 "/LPDDR5/LPDDR5_B.CA2")
			(pinfunction "R1.1")
			(pintype "passive")
		)
		(pad "2" smd roundrect
			(at -0.25 0.45 180)
			(size 0.25 0.5)
			(layers "F.Cu" "F.Mask" "F.Paste")
			(roundrect_rratio 0.25)
			(net 99 "/LPDDR5/LPDDR5_B.CA3")
			(pinfunction "R2.1")
			(pintype "passive")
		)
		(pad "3" smd roundrect
			(at 0.25 0.45 180)
			(size 0.25 0.5)
			(layers "F.Cu" "F.Mask" "F.Paste")
			(roundrect_rratio 0.25)
			(net 105 "/LPDDR5/LPDDR5_B.CA4")
			(pinfunction "R3.1")
			(pintype "passive")
		)
		(pad "4" smd roundrect
			(at 0.8875 0.45 180)
			(size 0.525 0.5)
			(layers "F.Cu" "F.Mask" "F.Paste")
			(roundrect_rratio 0.25)
			(net 101 "/LPDDR5/LPDDR5_B.CA5")
			(pinfunction "R4.1")
			(pintype "passive")
		)
		(pad "5" smd roundrect
			(at 0.8875 -0.45 180)
			(size 0.525 0.5)
			(layers "F.Cu" "F.Mask" "F.Paste")
			(roundrect_rratio 0.25)
			(net 14 "GND")
			(pinfunction "R4.2")
			(pintype "passive")
		)
		(pad "6" smd roundrect
			(at 0.25 -0.45 180)
			(size 0.25 0.5)
			(layers "F.Cu" "F.Mask" "F.Paste")
			(roundrect_rratio 0.25)
			(net 14 "GND")
			(pinfunction "R3.2")
			(pintype "passive")
		)
		(pad "7" smd roundrect
			(at -0.25 -0.45 180)
			(size 0.25 0.5)
			(layers "F.Cu" "F.Mask" "F.Paste")
			(roundrect_rratio 0.25)
			(net 14 "GND")
			(pinfunction "R2.2")
			(pintype "passive")
		)
		(pad "8" smd roundrect
			(at -0.8875 -0.45 180)
			(size 0.525 0.5)
			(layers "F.Cu" "F.Mask" "F.Paste")
			(roundrect_rratio 0.25)
			(net 14 "GND")
			(pinfunction "R1.2")
			(pintype "passive")
		)
	)
	(footprint "antmicro-footprints:R_0402_1005Metric"
		(layer "F.Cu")
		(at 161.55 63.85 -90)
		(descr "Resistor SMD 0402")
		(tags "resistor SMD 0402")
		(property "Reference" "R51"
			(at -1.15 0.65 90)
			(unlocked yes)
			(layer "F.SilkS")
			(effects
				(font
					(size 0.7 0.7)
					(thickness 0.15)
				)
				(justify right bottom)
			)
		)
		(property "Value" "R_3k9_0402"
			(at -1.011843 1.772047 90)
			(layer "F.Fab")
			(effects
				(font
					(size 0.7 0.7)
					(thickness 0.15)
				)
				(justify right bottom)
			)
		)
		(property "Author" "Antmicro"
			(at 97.7 225.4 0)
			(layer "F.Fab")
			(hide yes)
			(effects
				(font
					(size 1 1)
					(thickness 0.15)
				)
			)
		)
		(property "License" "Apache-2.0"
			(at 97.7 225.4 0)
			(layer "F.Fab")
			(hide yes)
			(effects
				(font
					(size 1 1)
					(thickness 0.15)
				)
			)
		)
		(property "MPN" "CR0402-FX-3901GLF"
			(at 97.7 225.4 0)
			(layer "F.Fab")
			(hide yes)
			(effects
				(font
					(size 1 1)
					(thickness 0.15)
				)
			)
		)
		(property "Manufacturer" "Bourns"
			(at 97.7 225.4 0)
			(layer "F.Fab")
			(hide yes)
			(effects
				(font
					(size 1 1)
					(thickness 0.15)
				)
			)
		)
		(property "Tolerance" "1%"
			(at 97.7 225.4 0)
			(layer "F.Fab")
			(hide yes)
			(effects
				(font
					(size 1 1)
					(thickness 0.15)
				)
			)
		)
		(property "Val" "3k9"
			(at 97.7 225.4 0)
			(layer "F.Fab")
			(hide yes)
			(effects
				(font
					(size 1 1)
					(thickness 0.15)
				)
			)
		)
		(sheetname "Power supply")
		(sheetfile "power_supply.kicad_sch")
		(attr smd)
		(fp_rect
			(start -0.93 -0.47)
			(end 0.93 0.47)
			(stroke
				(width 0.05)
				(type solid)
			)
			(fill no)
			(layer "F.CrtYd")
		)
		(fp_rect
			(start -0.5 -0.25)
			(end 0.5 0.25)
			(stroke
				(width 0.15)
				(type solid)
			)
			(fill no)
			(layer "F.Fab")
		)
		(pad "1" smd roundrect
			(at -0.485 0 270)
			(size 0.59 0.64)
			(layers "F.Cu" "F.Mask" "F.Paste")
			(roundrect_rratio 0.25)
			(net 53 "Net-(POT1-Pad3)")
			(pintype "passive")
		)
		(pad "2" smd roundrect
			(at 0.485 0 270)
			(size 0.59 0.64)
			(layers "F.Cu" "F.Mask" "F.Paste")
			(roundrect_rratio 0.25)
			(net 11 "/Power supply/VOUT")
			(pintype "passive")
		)
	)
)
